# T6G (Grand Teton) — schematic netlist excerpt (pin names and nets, part order shuffled) for the footprints in the layout excerpt that follows; sources: Cadence DE-HDL packaged netlist, KiCad conversion of 04192023_DAF0TMB3IC0_F0TG_MB_C_brd_V02_OCP.brd

R800  Q_RES  10K 1% CHIP  pkg 0402LF  page 83 : A = RST_PERST_E1S_0_N ; B = GND
R884  Q_RES  4.7K 5% CHIP  pkg 0201LF  page 342 : A = JTAG_TEST_MODE_RT_CPU1_P2 ; B = GND
R1739  Q_RES  0 5% CHIP  pkg 0402LF  page 171 : A = JTAG_SCM_MUX_R_TDO ; B = JTAG_SCM_MUX_TDO

(kicad_pcb
	(version 20260206)
	(generator "pcbnew")
	(generator_version "10.0")
	(general
		(thickness 1.6)
		(legacy_teardrops no)
	)
	(paper "A4")
	(title_block
		(title "04192023_DAF0TMB3IC0_F0TG_MB_C_brd_V02_OCP.brd")
		(comment 1 "Grand Teton / footprints 3690-3692 of 8354")
	)
	(layers
		(0 "F.Cu" signal "TOP")
		(4 "In1.Cu" signal "GND")
		(6 "In2.Cu" signal "IN1")
		(8 "In3.Cu" signal "GND1")
		(10 "In4.Cu" signal "IN2")
		(12 "In5.Cu" signal "GND2")
		(14 "In6.Cu" signal "IN3")
		(16 "In7.Cu" signal "GND3")
		(18 "In8.Cu" signal "VCC")
		(20 "In9.Cu" signal "VCC1")
		(22 "In10.Cu" signal "GND4")
		(24 "In11.Cu" signal "IN4")
		(26 "In12.Cu" signal "GND5")
		(28 "In13.Cu" signal "IN5")
		(30 "In14.Cu" signal "GND6")
		(32 "In15.Cu" signal "IN6")
		(34 "In16.Cu" signal "GND7")
		(2 "B.Cu" signal "BOTTOM")
		(9 "F.Adhes" user "F.Adhesive")
		(11 "B.Adhes" user "B.Adhesive")
		(13 "F.Paste" user "Package Geometry/Pastemask Top")
		(15 "B.Paste" user "Package Geometry/Pastemask Bottom")
		(5 "F.SilkS" user "Ref Des/Silkscreen Top")
		(7 "B.SilkS" user "Ref Des/Silkscreen Bottom")
		(1 "F.Mask" user "Board Geometry/Soldermask Top")
		(3 "B.Mask" user "Board Geometry/Soldermask Bottom")
		(17 "Dwgs.User" user "User.Drawings")
		(19 "Cmts.User" user "User.Comments")
		(21 "Eco1.User" user "User.Eco1")
		(23 "Eco2.User" user "User.Eco2")
		(25 "Edge.Cuts" user "Board Geometry/Outline")
		(27 "Margin" user)
		(31 "F.CrtYd" user "Package Geometry/Place Bound Top")
		(29 "B.CrtYd" user "Package Geometry/Place Bound Bottom")
		(35 "F.Fab" user "Ref Des/Assembly Top")
		(33 "B.Fab" user "Ref Des/Assembly Bottom")
	)
	(footprint ""
		(layer "F.Cu")
		(at 146.214846 -395.221206 -90)
		(property "Reference" "R884"
			(at 0 0 270)
			(layer "F.SilkS")
			(hide yes)
			(effects
				(font
					(size 1.27 1.27)
				)
			)
		)
		(property "Value" ""
			(at 0 0 270)
			(layer "F.Fab")
			(effects
				(font
					(size 1.27 1.27)
				)
			)
		)
		(duplicate_pad_numbers_are_jumpers no)
		(fp_line
			(start -0.32512 0.175006)
			(end -0.32512 -0.175006)
			(stroke
				(width 0.1)
				(type default)
			)
			(layer "F.Fab")
		)
		(fp_line
			(start 0.32512 0.175006)
			(end -0.32512 0.175006)
			(stroke
				(width 0.1)
				(type default)
			)
			(layer "F.Fab")
		)
		(fp_line
			(start -0.32512 -0.175006)
			(end 0.32512 -0.175006)
			(stroke
				(width 0.1)
				(type default)
			)
			(layer "F.Fab")
		)
		(fp_line
			(start 0.32512 -0.175006)
			(end 0.32512 0.175006)
			(stroke
				(width 0.1)
				(type default)
			)
			(layer "F.Fab")
		)
		(pad "1" smd rect
			(at -0.2667 0 270)
			(size 0.3048 0.381)
			(layers "F.Cu" "F.Mask" "F.Paste")
			(net "JTAG_TEST_MODE_RT_CPU1_P2")
		)
		(pad "2" smd rect
			(at 0.2667 0 90)
			(size 0.3048 0.381)
			(layers "F.Cu" "F.Mask" "F.Paste")
			(net "GND")
		)
	)
	(footprint ""
		(layer "F.Cu")
		(at 200.952608 -116.673376)
		(property "Reference" "R800"
			(at 0 0 0)
			(layer "F.SilkS")
			(hide yes)
			(effects
				(font
					(size 1.27 1.27)
				)
			)
		)
		(property "Value" ""
			(at 0 0 0)
			(layer "F.Fab")
			(effects
				(font
					(size 1.27 1.27)
				)
			)
		)
		(duplicate_pad_numbers_are_jumpers no)
		(fp_line
			(start -0.7874 -0.4064)
			(end 0.7874 -0.4064)
			(stroke
				(width 0.1524)
				(type default)
			)
			(layer "F.SilkS")
		)
		(fp_line
			(start -0.7874 0.4064)
			(end -0.7874 -0.4064)
			(stroke
				(width 0.1524)
				(type default)
			)
			(layer "F.SilkS")
		)
		(fp_line
			(start 0.7874 -0.4064)
			(end 0.7874 0.4064)
			(stroke
				(width 0.1524)
				(type default)
			)
			(layer "F.SilkS")
		)
		(fp_line
			(start 0.7874 0.4064)
			(end -0.7874 0.4064)
			(stroke
				(width 0.1524)
				(type default)
			)
			(layer "F.SilkS")
		)
		(fp_line
			(start -0.67945 -0.305054)
			(end -0.12065 -0.305054)
			(stroke
				(width 0.1)
				(type default)
			)
			(layer "F.Fab")
		)
		(fp_line
			(start -0.67945 0.3048)
			(end -0.67945 -0.305054)
			(stroke
				(width 0.1)
				(type default)
			)
			(layer "F.Fab")
		)
		(fp_line
			(start -0.12065 -0.305054)
			(end -0.12065 -0.2794)
			(stroke
				(width 0.1)
				(type default)
			)
			(layer "F.Fab")
		)
		(fp_line
			(start -0.12065 -0.2794)
			(end 0.12065 -0.2794)
			(stroke
				(width 0.1)
				(type default)
			)
			(layer "F.Fab")
		)
		(fp_line
			(start -0.12065 0.2794)
			(end -0.12065 0.3048)
			(stroke
				(width 0.1)
				(type default)
			)
			(layer "F.Fab")
		)
		(fp_line
			(start -0.12065 0.3048)
			(end -0.67945 0.3048)
			(stroke
				(width 0.1)
				(type default)
			)
			(layer "F.Fab")
		)
		(fp_line
			(start 0.120396 0.2794)
			(end -0.12065 0.2794)
			(stroke
				(width 0.1)
				(type default)
			)
			(layer "F.Fab")
		)
		(fp_line
			(start 0.120396 0.3048)
			(end 0.120396 0.2794)
			(stroke
				(width 0.1)
				(type default)
			)
			(layer "F.Fab")
		)
		(fp_line
			(start 0.12065 -0.3048)
			(end 0.67945 -0.3048)
			(stroke
				(width 0.1)
				(type default)
			)
			(layer "F.Fab")
		)
		(fp_line
			(start 0.12065 -0.2794)
			(end 0.12065 -0.3048)
			(stroke
				(width 0.1)
				(type default)
			)
			(layer "F.Fab")
		)
		(fp_line
			(start 0.67945 -0.3048)
			(end 0.67945 0.3048)
			(stroke
				(width 0.1)
				(type default)
			)
			(layer "F.Fab")
		)
		(fp_line
			(start 0.67945 0.3048)
			(end 0.120396 0.3048)
			(stroke
				(width 0.1)
				(type default)
			)
			(layer "F.Fab")
		)
		(pad "1" smd circle
			(at -0.40005 0)
			(size 0 0)
			(layers "F.Cu" "F.Mask" "F.Paste")
			(net "RST_PERST_E1S_0_N")
		)
		(pad "2" smd circle
			(at 0.40005 0)
			(size 0 0)
			(layers "F.Cu" "F.Mask" "F.Paste")
			(net "GND")
		)
	)
	(footprint ""
		(layer "F.Cu")
		(at 125.992636 -59.182 180)
		(property "Reference" "R1739"
			(at 0 0 180)
			(layer "F.SilkS")
			(hide yes)
			(effects
				(font
					(size 1.27 1.27)
				)
			)
		)
		(property "Value" ""
			(at 0 0 180)
			(layer "F.Fab")
			(effects
				(font
					(size 1.27 1.27)
				)
			)
		)
		(duplicate_pad_numbers_are_jumpers no)
		(fp_line
			(start 0.7874 0.4064)
			(end -0.7874 0.4064)
			(stroke
				(width 0.1524)
				(type default)
			)
			(layer "F.SilkS")
		)
		(fp_line
			(start 0.7874 -0.4064)
			(end 0.7874 0.4064)
			(stroke
				(width 0.1524)
				(type default)
			)
			(layer "F.SilkS")
		)
		(fp_line
			(start -0.7874 0.4064)
			(end -0.7874 -0.4064)
			(stroke
				(width 0.1524)
				(type default)
			)
			(layer "F.SilkS")
		)
		(fp_line
			(start -0.7874 -0.4064)
			(end 0.7874 -0.4064)
			(stroke
				(width 0.1524)
				(type default)
			)
			(layer "F.SilkS")
		)
		(fp_line
			(start 0.67945 0.3048)
			(end 0.120396 0.3048)
			(stroke
				(width 0.1)
				(type default)
			)
			(layer "F.Fab")
		)
		(fp_line
			(start 0.67945 -0.3048)
			(end 0.67945 0.3048)
			(stroke
				(width 0.1)
				(type default)
			)
			(layer "F.Fab")
		)
		(fp_line
			(start 0.12065 -0.2794)
			(end 0.12065 -0.3048)
			(stroke
				(width 0.1)
				(type default)
			)
			(layer "F.Fab")
		)
		(fp_line
			(start 0.12065 -0.3048)
			(end 0.67945 -0.3048)
			(stroke
				(width 0.1)
				(type default)
			)
			(layer "F.Fab")
		)
		(fp_line
			(start 0.120396 0.3048)
			(end 0.120396 0.2794)
			(stroke
				(width 0.1)
				(type default)
			)
			(layer "F.Fab")
		)
		(fp_line
			(start 0.120396 0.2794)
			(end -0.12065 0.2794)
			(stroke
				(width 0.1)
				(type default)
			)
			(layer "F.Fab")
		)
		(fp_line
			(start -0.12065 0.3048)
			(end -0.67945 0.3048)
			(stroke
				(width 0.1)
				(type default)
			)
			(layer "F.Fab")
		)
		(fp_line
			(start -0.12065 0.2794)
			(end -0.12065 0.3048)
			(stroke
				(width 0.1)
				(type default)
			)
			(layer "F.Fab")
		)
		(fp_line
			(start -0.12065 -0.2794)
			(end 0.12065 -0.2794)
			(stroke
				(width 0.1)
				(type default)
			)
			(layer "F.Fab")
		)
		(fp_line
			(start -0.12065 -0.305054)
			(end -0.12065 -0.2794)
			(stroke
				(width 0.1)
				(type default)
			)
			(layer "F.Fab")
		)
		(fp_line
			(start -0.67945 0.3048)
			(end -0.67945 -0.305054)
			(stroke
				(width 0.1)
				(type default)
			)
			(layer "F.Fab")
		)
		(fp_line
			(start -0.67945 -0.305054)
			(end -0.12065 -0.305054)
			(stroke
				(width 0.1)
				(type default)
			)
			(layer "F.Fab")
		)
		(pad "1" smd circle
			(at -0.40005 0 180)
			(size 0 0)
			(layers "F.Cu" "F.Mask" "F.Paste")
			(net "JTAG_SCM_MUX_R_TDO")
		)
		(pad "2" smd circle
			(at 0.40005 0 180)
			(size 0 0)
			(layers "F.Cu" "F.Mask" "F.Paste")
			(net "JTAG_SCM_MUX_TDO")
		)
	)
)
